# T6G (Grand Teton) — schematic netlist excerpt (pin names and nets, part order shuffled) for the footprints in the layout excerpt that follows; sources: Cadence DE-HDL packaged netlist, KiCad conversion of 04192023_DAF0TMB3IC0_F0TG_MB_C_brd_V02_OCP.brd

R8289  Q_RES  1K 1% EMPTY  pkg 0402LF  page 193 : A = PVDD18_S5_P0 ; B = SVID_PVDDCR_CPU0_P0_SVD_R
C883  Q_CAP_DIFFBUS  DIFF BUS_0.22UF 6.3V 20% X6S  pkg C0201  page 64 : \1\ = P5E_CPU0_P3_TX_C_DP<9> ; \2\ = P5E_CPU0_P3_TX_DP<9>
R1482  Q_RES  4.7K 5% EMPTY  pkg 0201LF  page 309 : A = P1V8_CPU0_RT_1D ; B = JTAG_TDI_RT_CPU0_P3
C398  Q_CAP  100UF 4V 20% X6S  pkg C0805  page 345 : A = P0V9_CPU1_RT2_2A ; B = GND

(kicad_pcb
	(version 20260206)
	(generator "pcbnew")
	(generator_version "10.0")
	(general
		(thickness 1.6)
		(legacy_teardrops no)
	)
	(paper "A4")
	(title_block
		(title "04192023_DAF0TMB3IC0_F0TG_MB_C_brd_V02_OCP.brd")
		(comment 1 "Grand Teton / footprints 352-355 of 8354")
	)
	(layers
		(0 "F.Cu" signal "TOP")
		(4 "In1.Cu" signal "GND")
		(6 "In2.Cu" signal "IN1")
		(8 "In3.Cu" signal "GND1")
		(10 "In4.Cu" signal "IN2")
		(12 "In5.Cu" signal "GND2")
		(14 "In6.Cu" signal "IN3")
		(16 "In7.Cu" signal "GND3")
		(18 "In8.Cu" signal "VCC")
		(20 "In9.Cu" signal "VCC1")
		(22 "In10.Cu" signal "GND4")
		(24 "In11.Cu" signal "IN4")
		(26 "In12.Cu" signal "GND5")
		(28 "In13.Cu" signal "IN5")
		(30 "In14.Cu" signal "GND6")
		(32 "In15.Cu" signal "IN6")
		(34 "In16.Cu" signal "GND7")
		(2 "B.Cu" signal "BOTTOM")
		(9 "F.Adhes" user "F.Adhesive")
		(11 "B.Adhes" user "B.Adhesive")
		(13 "F.Paste" user "Package Geometry/Pastemask Top")
		(15 "B.Paste" user "Package Geometry/Pastemask Bottom")
		(5 "F.SilkS" user "Ref Des/Silkscreen Top")
		(7 "B.SilkS" user "Ref Des/Silkscreen Bottom")
		(1 "F.Mask" user "Board Geometry/Soldermask Top")
		(3 "B.Mask" user "Board Geometry/Soldermask Bottom")
		(17 "Dwgs.User" user "User.Drawings")
		(19 "Cmts.User" user "User.Comments")
		(21 "Eco1.User" user "User.Eco1")
		(23 "Eco2.User" user "User.Eco2")
		(25 "Edge.Cuts" user "Board Geometry/Outline")
		(27 "Margin" user)
		(31 "F.CrtYd" user "Package Geometry/Place Bound Top")
		(29 "B.CrtYd" user "Package Geometry/Place Bound Bottom")
		(35 "F.Fab" user "Ref Des/Assembly Top")
		(33 "B.Fab" user "Ref Des/Assembly Bottom")
	)
	(footprint ""
		(layer "F.Cu")
		(at 425.3484 -421.64 90)
		(property "Reference" "R1482"
			(at 0 0 90)
			(layer "F.SilkS")
			(hide yes)
			(effects
				(font
					(size 1.27 1.27)
				)
			)
		)
		(property "Value" ""
			(at 0 0 90)
			(layer "F.Fab")
			(effects
				(font
					(size 1.27 1.27)
				)
			)
		)
		(duplicate_pad_numbers_are_jumpers no)
		(fp_line
			(start 0.32512 -0.175006)
			(end 0.32512 0.175006)
			(stroke
				(width 0.1)
				(type default)
			)
			(layer "F.Fab")
		)
		(fp_line
			(start -0.32512 -0.175006)
			(end 0.32512 -0.175006)
			(stroke
				(width 0.1)
				(type default)
			)
			(layer "F.Fab")
		)
		(fp_line
			(start 0.32512 0.175006)
			(end -0.32512 0.175006)
			(stroke
				(width 0.1)
				(type default)
			)
			(layer "F.Fab")
		)
		(fp_line
			(start -0.32512 0.175006)
			(end -0.32512 -0.175006)
			(stroke
				(width 0.1)
				(type default)
			)
			(layer "F.Fab")
		)
		(pad "1" smd rect
			(at -0.2667 0 90)
			(size 0.3048 0.381)
			(layers "F.Cu" "F.Mask" "F.Paste")
			(net "P1V8_CPU0_RT_1D")
		)
		(pad "2" smd rect
			(at 0.2667 0 270)
			(size 0.3048 0.381)
			(layers "F.Cu" "F.Mask" "F.Paste")
			(net "JTAG_TDI_RT_CPU0_P3")
		)
	)
	(footprint ""
		(layer "F.Cu")
		(at 381.405892 -378.95403 -90)
		(property "Reference" "C883"
			(at 0 0 270)
			(layer "F.SilkS")
			(hide yes)
			(effects
				(font
					(size 1.27 1.27)
				)
			)
		)
		(property "Value" ""
			(at 0 0 270)
			(layer "F.Fab")
			(effects
				(font
					(size 1.27 1.27)
				)
			)
		)
		(duplicate_pad_numbers_are_jumpers no)
		(fp_line
			(start -0.299974 0.150114)
			(end -0.299974 -0.150114)
			(stroke
				(width 0.1)
				(type default)
			)
			(layer "F.Fab")
		)
		(fp_line
			(start 0.299974 0.150114)
			(end -0.299974 0.150114)
			(stroke
				(width 0.1)
				(type default)
			)
			(layer "F.Fab")
		)
		(fp_line
			(start -0.299974 -0.150114)
			(end 0.299974 -0.150114)
			(stroke
				(width 0.1)
				(type default)
			)
			(layer "F.Fab")
		)
		(fp_line
			(start 0.299974 -0.150114)
			(end 0.299974 0.150114)
			(stroke
				(width 0.1)
				(type default)
			)
			(layer "F.Fab")
		)
		(pad "1" smd rect
			(at -0.2667 0 270)
			(size 0.3048 0.381)
			(layers "F.Cu" "F.Mask" "F.Paste")
			(net "P5E_CPU0_P3_TX_C_DP<9>")
		)
		(pad "2" smd rect
			(at 0.2667 0 270)
			(size 0.3048 0.381)
			(layers "F.Cu" "F.Mask" "F.Paste")
			(net "P5E_CPU0_P3_TX_DP<9>")
		)
	)
	(footprint ""
		(layer "F.Cu")
		(at 170.213782 -392.074146)
		(property "Reference" "C398"
			(at 0 0 0)
			(layer "F.SilkS")
			(hide yes)
			(effects
				(font
					(size 1.27 1.27)
				)
			)
		)
		(property "Value" ""
			(at 0 0 0)
			(layer "F.Fab")
			(effects
				(font
					(size 1.27 1.27)
				)
			)
		)
		(duplicate_pad_numbers_are_jumpers no)
		(fp_line
			(start -1.524 -0.762)
			(end 1.524 -0.762)
			(stroke
				(width 0.1524)
				(type default)
			)
			(layer "F.SilkS")
		)
		(fp_line
			(start -1.524 0.762)
			(end -1.524 -0.762)
			(stroke
				(width 0.1524)
				(type default)
			)
			(layer "F.SilkS")
		)
		(fp_line
			(start 1.524 -0.762)
			(end 1.524 0.762)
			(stroke
				(width 0.1524)
				(type default)
			)
			(layer "F.SilkS")
		)
		(fp_line
			(start 1.524 0.762)
			(end -1.524 0.762)
			(stroke
				(width 0.1524)
				(type default)
			)
			(layer "F.SilkS")
		)
		(fp_line
			(start -1.1049 -0.724916)
			(end -1.1049 0.724916)
			(stroke
				(width 0.1)
				(type default)
			)
			(layer "F.Fab")
		)
		(fp_line
			(start -1.1049 0.724916)
			(end 1.1049 0.724916)
			(stroke
				(width 0.1)
				(type default)
			)
			(layer "F.Fab")
		)
		(fp_line
			(start 1.1049 -0.724916)
			(end -1.1049 -0.724916)
			(stroke
				(width 0.1)
				(type default)
			)
			(layer "F.Fab")
		)
		(fp_line
			(start 1.1049 0.724916)
			(end 1.1049 -0.724916)
			(stroke
				(width 0.1)
				(type default)
			)
			(layer "F.Fab")
		)
		(pad "1" smd rect
			(at -0.889 0 180)
			(size 1.016 1.27)
			(layers "F.Cu" "F.Mask" "F.Paste")
			(net "P0V9_CPU1_RT2_2A")
		)
		(pad "2" smd rect
			(at 0.889 0 180)
			(size 1.016 1.27)
			(layers "F.Cu" "F.Mask" "F.Paste")
			(net "GND")
		)
	)
	(footprint ""
		(layer "F.Cu")
		(at 372.937278 -144.520158 180)
		(property "Reference" "R8289"
			(at 0 0 180)
			(layer "F.SilkS")
			(hide yes)
			(effects
				(font
					(size 1.27 1.27)
				)
			)
		)
		(property "Value" ""
			(at 0 0 180)
			(layer "F.Fab")
			(effects
				(font
					(size 1.27 1.27)
				)
			)
		)
		(duplicate_pad_numbers_are_jumpers no)
		(fp_line
			(start 0.7874 0.4064)
			(end -0.7874 0.4064)
			(stroke
				(width 0.1524)
				(type default)
			)
			(layer "F.SilkS")
		)
		(fp_line
			(start 0.7874 -0.4064)
			(end 0.7874 0.4064)
			(stroke
				(width 0.1524)
				(type default)
			)
			(layer "F.SilkS")
		)
		(fp_line
			(start -0.7874 0.4064)
			(end -0.7874 -0.4064)
			(stroke
				(width 0.1524)
				(type default)
			)
			(layer "F.SilkS")
		)
		(fp_line
			(start -0.7874 -0.4064)
			(end 0.7874 -0.4064)
			(stroke
				(width 0.1524)
				(type default)
			)
			(layer "F.SilkS")
		)
		(fp_line
			(start 0.67945 0.3048)
			(end 0.120396 0.3048)
			(stroke
				(width 0.1)
				(type default)
			)
			(layer "F.Fab")
		)
		(fp_line
			(start 0.67945 -0.3048)
			(end 0.67945 0.3048)
			(stroke
				(width 0.1)
				(type default)
			)
			(layer "F.Fab")
		)
		(fp_line
			(start 0.12065 -0.2794)
			(end 0.12065 -0.3048)
			(stroke
				(width 0.1)
				(type default)
			)
			(layer "F.Fab")
		)
		(fp_line
			(start 0.12065 -0.3048)
			(end 0.67945 -0.3048)
			(stroke
				(width 0.1)
				(type default)
			)
			(layer "F.Fab")
		)
		(fp_line
			(start 0.120396 0.3048)
			(end 0.120396 0.2794)
			(stroke
				(width 0.1)
				(type default)
			)
			(layer "F.Fab")
		)
		(fp_line
			(start 0.120396 0.2794)
			(end -0.12065 0.2794)
			(stroke
				(width 0.1)
				(type default)
			)
			(layer "F.Fab")
		)
		(fp_line
			(start -0.12065 0.3048)
			(end -0.67945 0.3048)
			(stroke
				(width 0.1)
				(type default)
			)
			(layer "F.Fab")
		)
		(fp_line
			(start -0.12065 0.2794)
			(end -0.12065 0.3048)
			(stroke
				(width 0.1)
				(type default)
			)
			(layer "F.Fab")
		)
		(fp_line
			(start -0.12065 -0.2794)
			(end 0.12065 -0.2794)
			(stroke
				(width 0.1)
				(type default)
			)
			(layer "F.Fab")
		)
		(fp_line
			(start -0.12065 -0.305054)
			(end -0.12065 -0.2794)
			(stroke
				(width 0.1)
				(type default)
			)
			(layer "F.Fab")
		)
		(fp_line
			(start -0.67945 0.3048)
			(end -0.67945 -0.305054)
			(stroke
				(width 0.1)
				(type default)
			)
			(layer "F.Fab")
		)
		(fp_line
			(start -0.67945 -0.305054)
			(end -0.12065 -0.305054)
			(stroke
				(width 0.1)
				(type default)
			)
			(layer "F.Fab")
		)
		(pad "1" smd circle
			(at -0.40005 0 180)
			(size 0 0)
			(layers "F.Cu" "F.Mask" "F.Paste")
			(net "PVDD18_S5_P0")
		)
		(pad "2" smd circle
			(at 0.40005 0 180)
			(size 0 0)
			(layers "F.Cu" "F.Mask" "F.Paste")
			(net "SVID_PVDDCR_CPU0_P0_SVD_R")
		)
	)
)
